(kicad_pcb
	(version 20260206)
	(generator "pcbnew")
	(generator_version "10.0")
	(general
		(thickness 1.6)
		(legacy_teardrops no)
	)
	(paper "A4")
	(title_block
		(title "Bryce Canyon_IOM_IOC_16318-2_OCP.brd")
		(comment 1 "Bryce Canyon / footprints 300-306 of 1605")
	)
	(layers
		(0 "F.Cu" signal "TOP")
		(4 "In1.Cu" signal "L2GND")
		(6 "In2.Cu" signal "L3")
		(8 "In3.Cu" signal "L4VCC")
		(10 "In4.Cu" signal "L5VCC")
		(12 "In5.Cu" signal "L6")
		(14 "In6.Cu" signal "L7GND")
		(2 "B.Cu" signal "BOTTOM")
		(9 "F.Adhes" user "F.Adhesive")
		(11 "B.Adhes" user "B.Adhesive")
		(13 "F.Paste" user "Package Geometry/Pastemask Top")
		(15 "B.Paste" user "Package Geometry/Pastemask Bottom")
		(5 "F.SilkS" user "Ref Des/Silkscreen Top")
		(7 "B.SilkS" user "Ref Des/Silkscreen Bottom")
		(1 "F.Mask" user "Board Geometry/Soldermask Top")
		(3 "B.Mask" user "Board Geometry/Soldermask Bottom")
		(17 "Dwgs.User" user "User.Drawings")
		(19 "Cmts.User" user "User.Comments")
		(21 "Eco1.User" user "User.Eco1")
		(23 "Eco2.User" user "User.Eco2")
		(25 "Edge.Cuts" user "Board Geometry/Outline")
		(27 "Margin" user)
		(31 "F.CrtYd" user "Package Geometry/Place Bound Top")
		(29 "B.CrtYd" user "Package Geometry/Place Bound Bottom")
		(35 "F.Fab" user "Ref Des/Assembly Top")
		(33 "B.Fab" user "Ref Des/Assembly Bottom")
	)
	(footprint ""
		(layer "F.Cu")
		(at 20.773136 -170.1038)
		(property "Reference" "C230"
			(at 0 0 0)
			(layer "F.SilkS")
			(hide yes)
			(effects
				(font
					(size 1.27 1.27)
				)
			)
		)
		(property "Value" "SCD1U16V2KX-3GP"
			(at 1.1811 -2.7051 0)
			(unlocked yes)
			(layer "F.Fab")
			(hide yes)
			(effects
				(font
					(size 1.016 1.016)
					(thickness 0.1524)
				)
			)
		)
		(property "Device Type" "C402H22"
			(at 1.1811 -4.2291 0)
			(unlocked yes)
			(layer "F.Fab")
			(hide yes)
			(effects
				(font
					(size 1.016 1.016)
					(thickness 0.1524)
				)
			)
		)
		(duplicate_pad_numbers_are_jumpers no)
		(fp_rect
			(start -0.4318 0.9525)
			(end 0.4318 -0.9525)
			(stroke
				(width 0)
				(type default)
			)
			(fill no)
			(layer "F.CrtYd")
		)
		(fp_rect
			(start -0.4318 0.9525)
			(end 0.4318 -0.9525)
			(stroke
				(width 0)
				(type default)
			)
			(fill no)
			(layer "F.Fab")
		)
		(pad "1" smd custom
			(at 0 -0.4445)
			(size 0.1524 0.1524)
			(layers "F.Cu" "F.Mask" "F.Paste")
			(net "P1V8_STBY")
			(options
				(clearance outline)
				(anchor circle)
			)
			(primitives
				(gr_poly
					(pts
						(arc
							(start 0.3048 -0.2032)
							(mid 0.275042 -0.275042)
							(end 0.2032 -0.3048)
						)
						(arc
							(start -0.2032 -0.3048)
							(mid -0.275042 -0.275042)
							(end -0.3048 -0.2032)
						)
						(arc
							(start -0.3048 0.2032)
							(mid -0.275042 0.275042)
							(end -0.2032 0.3048)
						)
						(arc
							(start 0.2032 0.3048)
							(mid 0.275042 0.275042)
							(end 0.3048 0.2032)
						)
					)
					(width 0)
					(fill yes)
				)
			)
		)
		(pad "2" smd custom
			(at 0 0.4445)
			(size 0.1524 0.1524)
			(layers "F.Cu" "F.Mask" "F.Paste")
			(net "GND")
			(options
				(clearance outline)
				(anchor circle)
			)
			(primitives
				(gr_poly
					(pts
						(arc
							(start 0.3048 -0.2032)
							(mid 0.275042 -0.275042)
							(end 0.2032 -0.3048)
						)
						(arc
							(start -0.2032 -0.3048)
							(mid -0.275042 -0.275042)
							(end -0.3048 -0.2032)
						)
						(arc
							(start -0.3048 0.2032)
							(mid -0.275042 0.275042)
							(end -0.2032 0.3048)
						)
						(arc
							(start 0.2032 0.3048)
							(mid 0.275042 0.275042)
							(end 0.3048 0.2032)
						)
					)
					(width 0)
					(fill yes)
				)
			)
		)
	)
	(footprint ""
		(layer "F.Cu")
		(at 46.054772 -117.791992 90)
		(property "Reference" "C36"
			(at 0 0 90)
			(layer "F.SilkS")
			(hide yes)
			(effects
				(font
					(size 1.27 1.27)
				)
			)
		)
		(property "Value" "SCD1U16V2KX-3GP"
			(at 1.1811 -2.7051 90)
			(unlocked yes)
			(layer "F.Fab")
			(hide yes)
			(effects
				(font
					(size 1.016 1.016)
					(thickness 0.1524)
				)
			)
		)
		(property "Device Type" "C402H22"
			(at 1.1811 -4.2291 90)
			(unlocked yes)
			(layer "F.Fab")
			(hide yes)
			(effects
				(font
					(size 1.016 1.016)
					(thickness 0.1524)
				)
			)
		)
		(duplicate_pad_numbers_are_jumpers no)
		(fp_rect
			(start -0.4318 0.9525)
			(end 0.4318 -0.9525)
			(stroke
				(width 0)
				(type default)
			)
			(fill no)
			(layer "F.CrtYd")
		)
		(fp_rect
			(start -0.4318 0.9525)
			(end 0.4318 -0.9525)
			(stroke
				(width 0)
				(type default)
			)
			(fill no)
			(layer "F.Fab")
		)
		(pad "1" smd custom
			(at 0 -0.4445 90)
			(size 0.1524 0.1524)
			(layers "F.Cu" "F.Mask" "F.Paste")
			(net "P3V3_STBY")
			(options
				(clearance outline)
				(anchor circle)
			)
			(primitives
				(gr_poly
					(pts
						(arc
							(start 0.3048 -0.2032)
							(mid 0.275042 -0.275042)
							(end 0.2032 -0.3048)
						)
						(arc
							(start -0.2032 -0.3048)
							(mid -0.275042 -0.275042)
							(end -0.3048 -0.2032)
						)
						(arc
							(start -0.3048 0.2032)
							(mid -0.275042 0.275042)
							(end -0.2032 0.3048)
						)
						(arc
							(start 0.2032 0.3048)
							(mid 0.275042 0.275042)
							(end 0.3048 0.2032)
						)
					)
					(width 0)
					(fill yes)
				)
			)
		)
		(pad "2" smd custom
			(at 0 0.4445 90)
			(size 0.1524 0.1524)
			(layers "F.Cu" "F.Mask" "F.Paste")
			(net "GND")
			(options
				(clearance outline)
				(anchor circle)
			)
			(primitives
				(gr_poly
					(pts
						(arc
							(start 0.3048 -0.2032)
							(mid 0.275042 -0.275042)
							(end 0.2032 -0.3048)
						)
						(arc
							(start -0.2032 -0.3048)
							(mid -0.275042 -0.275042)
							(end -0.3048 -0.2032)
						)
						(arc
							(start -0.3048 0.2032)
							(mid -0.275042 0.275042)
							(end -0.2032 0.3048)
						)
						(arc
							(start 0.2032 0.3048)
							(mid 0.275042 0.275042)
							(end 0.3048 0.2032)
						)
					)
					(width 0)
					(fill yes)
				)
			)
		)
	)
	(footprint ""
		(layer "F.Cu")
		(at 193.6496 -120.8786)
		(property "Reference" "C267"
			(at 0 0 0)
			(layer "F.SilkS")
			(hide yes)
			(effects
				(font
					(size 1.27 1.27)
				)
			)
		)
		(property "Value" "SC1U25V3KX-GP"
			(at 0 -2.8194 0)
			(unlocked yes)
			(layer "F.Fab")
			(hide yes)
			(effects
				(font
					(size 1.016 1.016)
					(thickness 0.1524)
				)
			)
		)
		(property "Device Type" "C603H36"
			(at 0 -4.3434 0)
			(unlocked yes)
			(layer "F.Fab")
			(hide yes)
			(effects
				(font
					(size 1.016 1.016)
					(thickness 0.1524)
				)
			)
		)
		(duplicate_pad_numbers_are_jumpers no)
		(fp_line
			(start 0.508 0)
			(end -0.508 0)
			(stroke
				(width 0.2032)
				(type default)
			)
			(layer "F.SilkS")
		)
		(fp_rect
			(start -0.5842 1.3335)
			(end 0.5842 -1.3335)
			(stroke
				(width 0)
				(type default)
			)
			(fill no)
			(layer "F.CrtYd")
		)
		(fp_rect
			(start -0.5842 1.3335)
			(end 0.5842 -1.3335)
			(stroke
				(width 0)
				(type default)
			)
			(fill no)
			(layer "F.Fab")
		)
		(pad "1" smd custom
			(at 0 -0.762)
			(size 0.2159 0.2159)
			(layers "F.Cu" "F.Mask" "F.Paste")
			(net "VT235_BST")
			(options
				(clearance outline)
				(anchor circle)
			)
			(primitives
				(gr_poly
					(pts
						(arc
							(start -0.3302 -0.4318)
							(mid -0.402042 -0.402042)
							(end -0.4318 -0.3302)
						)
						(arc
							(start -0.4318 0.3302)
							(mid -0.402042 0.402042)
							(end -0.3302 0.4318)
						)
						(arc
							(start 0.3302 0.4318)
							(mid 0.402042 0.402042)
							(end 0.4318 0.3302)
						)
						(arc
							(start 0.4318 -0.3302)
							(mid 0.402042 -0.402042)
							(end 0.3302 -0.4318)
						)
					)
					(width 0)
					(fill yes)
				)
			)
		)
		(pad "2" smd custom
			(at 0 0.762)
			(size 0.2159 0.2159)
			(layers "F.Cu" "F.Mask" "F.Paste")
			(net "VT235_VX")
			(options
				(clearance outline)
				(anchor circle)
			)
			(primitives
				(gr_poly
					(pts
						(arc
							(start -0.3302 -0.4318)
							(mid -0.402042 -0.402042)
							(end -0.4318 -0.3302)
						)
						(arc
							(start -0.4318 0.3302)
							(mid -0.402042 0.402042)
							(end -0.3302 0.4318)
						)
						(arc
							(start 0.3302 0.4318)
							(mid 0.402042 0.402042)
							(end 0.4318 0.3302)
						)
						(arc
							(start 0.4318 -0.3302)
							(mid 0.402042 -0.402042)
							(end 0.3302 -0.4318)
						)
					)
					(width 0)
					(fill yes)
				)
			)
		)
	)
	(footprint ""
		(layer "F.Cu")
		(at 60.071 -160.8328 90)
		(property "Reference" "R392"
			(at 0 0 90)
			(layer "F.SilkS")
			(hide yes)
			(effects
				(font
					(size 1.27 1.27)
				)
			)
		)
		(property "Value" "4K7R2F-GP"
			(at 0.064008 -3.993896 90)
			(unlocked yes)
			(layer "F.Fab")
			(hide yes)
			(effects
				(font
					(size 1.016 1.016)
					(thickness 0.1524)
				)
			)
		)
		(property "Device Type" "R402H16"
			(at 0.064008 -5.517896 90)
			(unlocked yes)
			(layer "F.Fab")
			(hide yes)
			(effects
				(font
					(size 1.016 1.016)
					(thickness 0.1524)
				)
			)
		)
		(duplicate_pad_numbers_are_jumpers no)
		(fp_line
			(start 0.508 -0.9398)
			(end -0.508 -0.9398)
			(stroke
				(width 0.1524)
				(type default)
			)
			(layer "F.SilkS")
		)
		(fp_line
			(start -0.508 -0.9398)
			(end -0.508 0.9398)
			(stroke
				(width 0.1524)
				(type default)
			)
			(layer "F.SilkS")
		)
		(fp_rect
			(start -0.508 0.9398)
			(end 0.508 -0.9398)
			(stroke
				(width 0)
				(type default)
			)
			(fill no)
			(layer "F.CrtYd")
		)
		(fp_rect
			(start -0.508 0.9398)
			(end 0.508 -0.9398)
			(stroke
				(width 0)
				(type default)
			)
			(fill no)
			(layer "F.Fab")
		)
		(pad "1" smd custom
			(at 0 -0.4445 90)
			(size 0.1397 0.1397)
			(layers "F.Cu" "F.Mask" "F.Paste")
			(net "P3V3_STBY")
			(options
				(clearance outline)
				(anchor circle)
			)
			(primitives
				(gr_poly
					(pts
						(arc
							(start -0.1778 -0.2794)
							(mid -0.249642 -0.249642)
							(end -0.2794 -0.1778)
						)
						(arc
							(start -0.2794 0.1778)
							(mid -0.249642 0.249642)
							(end -0.1778 0.2794)
						)
						(arc
							(start 0.1778 0.2794)
							(mid 0.249642 0.249642)
							(end 0.2794 0.1778)
						)
						(arc
							(start 0.2794 -0.1778)
							(mid 0.249642 -0.249642)
							(end 0.1778 -0.2794)
						)
					)
					(width 0)
					(fill yes)
				)
			)
		)
		(pad "2" smd custom
			(at 0 0.4445 90)
			(size 0.1397 0.1397)
			(layers "F.Cu" "F.Mask" "F.Paste")
			(net "MAC2_TXD1")
			(options
				(clearance outline)
				(anchor circle)
			)
			(primitives
				(gr_poly
					(pts
						(arc
							(start -0.1778 -0.2794)
							(mid -0.249642 -0.249642)
							(end -0.2794 -0.1778)
						)
						(arc
							(start -0.2794 0.1778)
							(mid -0.249642 0.249642)
							(end -0.1778 0.2794)
						)
						(arc
							(start 0.1778 0.2794)
							(mid 0.249642 0.249642)
							(end 0.2794 0.1778)
						)
						(arc
							(start 0.2794 -0.1778)
							(mid 0.249642 -0.249642)
							(end 0.1778 -0.2794)
						)
					)
					(width 0)
					(fill yes)
				)
			)
		)
	)
	(footprint ""
		(layer "F.Cu")
		(at 66.2686 -169.1894 90)
		(property "Reference" "C38"
			(at 0 0 90)
			(layer "F.SilkS")
			(hide yes)
			(effects
				(font
					(size 1.27 1.27)
				)
			)
		)
		(property "Value" "SCD1U16V2KX-3GP"
			(at 1.1811 -2.7051 90)
			(unlocked yes)
			(layer "F.Fab")
			(hide yes)
			(effects
				(font
					(size 1.016 1.016)
					(thickness 0.1524)
				)
			)
		)
		(property "Device Type" "C402H22"
			(at 1.1811 -4.2291 90)
			(unlocked yes)
			(layer "F.Fab")
			(hide yes)
			(effects
				(font
					(size 1.016 1.016)
					(thickness 0.1524)
				)
			)
		)
		(duplicate_pad_numbers_are_jumpers no)
		(fp_rect
			(start -0.4318 0.9525)
			(end 0.4318 -0.9525)
			(stroke
				(width 0)
				(type default)
			)
			(fill no)
			(layer "F.CrtYd")
		)
		(fp_rect
			(start -0.4318 0.9525)
			(end 0.4318 -0.9525)
			(stroke
				(width 0)
				(type default)
			)
			(fill no)
			(layer "F.Fab")
		)
		(pad "1" smd custom
			(at 0 -0.4445 90)
			(size 0.1524 0.1524)
			(layers "F.Cu" "F.Mask" "F.Paste")
			(net "Q4_G")
			(options
				(clearance outline)
				(anchor circle)
			)
			(primitives
				(gr_poly
					(pts
						(arc
							(start 0.3048 -0.2032)
							(mid 0.275042 -0.275042)
							(end 0.2032 -0.3048)
						)
						(arc
							(start -0.2032 -0.3048)
							(mid -0.275042 -0.275042)
							(end -0.3048 -0.2032)
						)
						(arc
							(start -0.3048 0.2032)
							(mid -0.275042 0.275042)
							(end -0.2032 0.3048)
						)
						(arc
							(start 0.2032 0.3048)
							(mid 0.275042 0.275042)
							(end 0.3048 0.2032)
						)
					)
					(width 0)
					(fill yes)
				)
			)
		)
		(pad "2" smd custom
			(at 0 0.4445 90)
			(size 0.1524 0.1524)
			(layers "F.Cu" "F.Mask" "F.Paste")
			(net "GND")
			(options
				(clearance outline)
				(anchor circle)
			)
			(primitives
				(gr_poly
					(pts
						(arc
							(start 0.3048 -0.2032)
							(mid 0.275042 -0.275042)
							(end 0.2032 -0.3048)
						)
						(arc
							(start -0.2032 -0.3048)
							(mid -0.275042 -0.275042)
							(end -0.3048 -0.2032)
						)
						(arc
							(start -0.3048 0.2032)
							(mid -0.275042 0.275042)
							(end -0.2032 0.3048)
						)
						(arc
							(start 0.2032 0.3048)
							(mid 0.275042 0.275042)
							(end 0.3048 0.2032)
						)
					)
					(width 0)
					(fill yes)
				)
			)
		)
	)
	(footprint ""
		(layer "F.Cu")
		(at 204.533246 -132.480558)
		(property "Reference" "R546"
			(at 0 0 0)
			(layer "F.SilkS")
			(hide yes)
			(effects
				(font
					(size 1.27 1.27)
				)
			)
		)
		(property "Value" "10KR2F-2-GP"
			(at 0.064008 -3.993896 0)
			(unlocked yes)
			(layer "F.Fab")
			(hide yes)
			(effects
				(font
					(size 1.016 1.016)
					(thickness 0.1524)
				)
			)
		)
		(property "Device Type" "R402H16"
			(at 0.064008 -5.517896 0)
			(unlocked yes)
			(layer "F.Fab")
			(hide yes)
			(effects
				(font
					(size 1.016 1.016)
					(thickness 0.1524)
				)
			)
		)
		(duplicate_pad_numbers_are_jumpers no)
		(fp_line
			(start -0.508 -0.9398)
			(end -0.508 0.9398)
			(stroke
				(width 0.1524)
				(type default)
			)
			(layer "F.SilkS")
		)
		(fp_line
			(start 0.508 -0.9398)
			(end -0.508 -0.9398)
			(stroke
				(width 0.1524)
				(type default)
			)
			(layer "F.SilkS")
		)
		(fp_rect
			(start -0.508 0.9398)
			(end 0.508 -0.9398)
			(stroke
				(width 0)
				(type default)
			)
			(fill no)
			(layer "F.CrtYd")
		)
		(fp_rect
			(start -0.508 0.9398)
			(end 0.508 -0.9398)
			(stroke
				(width 0)
				(type default)
			)
			(fill no)
			(layer "F.Fab")
		)
		(pad "1" smd custom
			(at 0 -0.4445)
			(size 0.1397 0.1397)
			(layers "F.Cu" "F.Mask" "F.Paste")
			(net "P3V3_STBY")
			(options
				(clearance outline)
				(anchor circle)
			)
			(primitives
				(gr_poly
					(pts
						(arc
							(start -0.1778 -0.2794)
							(mid -0.249642 -0.249642)
							(end -0.2794 -0.1778)
						)
						(arc
							(start -0.2794 0.1778)
							(mid -0.249642 0.249642)
							(end -0.1778 0.2794)
						)
						(arc
							(start 0.1778 0.2794)
							(mid 0.249642 0.249642)
							(end 0.2794 0.1778)
						)
						(arc
							(start 0.2794 -0.1778)
							(mid 0.249642 -0.249642)
							(end 0.1778 -0.2794)
						)
					)
					(width 0)
					(fill yes)
				)
			)
		)
		(pad "2" smd custom
			(at 0 0.4445)
			(size 0.1397 0.1397)
			(layers "F.Cu" "F.Mask" "F.Paste")
			(net "PWRGD_P1V5")
			(options
				(clearance outline)
				(anchor circle)
			)
			(primitives
				(gr_poly
					(pts
						(arc
							(start -0.1778 -0.2794)
							(mid -0.249642 -0.249642)
							(end -0.2794 -0.1778)
						)
						(arc
							(start -0.2794 0.1778)
							(mid -0.249642 0.249642)
							(end -0.1778 0.2794)
						)
						(arc
							(start 0.1778 0.2794)
							(mid 0.249642 0.249642)
							(end 0.2794 0.1778)
						)
						(arc
							(start 0.2794 -0.1778)
							(mid 0.249642 -0.249642)
							(end 0.1778 -0.2794)
						)
					)
					(width 0)
					(fill yes)
				)
			)
		)
	)
	(footprint ""
		(layer "F.Cu")
		(at 167.270684 -116.032534 90)
		(property "Reference" "PQ5"
			(at 0 0 90)
			(layer "F.SilkS")
			(hide yes)
			(effects
				(font
					(size 1.27 1.27)
				)
			)
		)
		(property "Value" "FDS8878-G-GP"
			(at -3.707384 -1.5367 90)
			(unlocked yes)
			(layer "F.Fab")
			(hide yes)
			(effects
				(font
					(size 1.016 1.016)
					(thickness 0.1524)
				)
			)
		)
		(property "Device Type" "SOIC8H69"
			(at -3.707384 -3.0607 90)
			(unlocked yes)
			(layer "F.Fab")
			(hide yes)
			(effects
				(font
					(size 1.016 1.016)
					(thickness 0.1524)
				)
			)
		)
		(duplicate_pad_numbers_are_jumpers no)
		(fp_line
			(start 2.1336 -1.4224)
			(end -2.7432 -1.4224)
			(stroke
				(width 0.1524)
				(type default)
			)
			(layer "F.SilkS")
		)
		(fp_line
			(start -2.7432 -1.4224)
			(end -2.7432 1.4224)
			(stroke
				(width 0.1524)
				(type default)
			)
			(layer "F.SilkS")
		)
		(fp_line
			(start -2.7178 -0.508)
			(end -2.1844 -0.0508)
			(stroke
				(width 0.1524)
				(type default)
			)
			(layer "F.SilkS")
		)
		(fp_line
			(start -2.1844 -0.0508)
			(end -2.7178 0.508)
			(stroke
				(width 0.1524)
				(type default)
			)
			(layer "F.SilkS")
		)
		(fp_line
			(start 2.1336 1.4224)
			(end 2.1336 -1.4224)
			(stroke
				(width 0.1524)
				(type default)
			)
			(layer "F.SilkS")
		)
		(fp_line
			(start -2.7432 1.4224)
			(end 2.1336 1.4224)
			(stroke
				(width 0.1524)
				(type default)
			)
			(layer "F.SilkS")
		)
		(fp_line
			(start -2.7432 1.4224)
			(end -2.6416 1.4224)
			(stroke
				(width 0.1524)
				(type default)
			)
			(layer "F.SilkS")
		)
		(fp_line
			(start -2.6289 3.4417)
			(end -2.6289 1.4732)
			(stroke
				(width 0.381)
				(type default)
			)
			(layer "F.SilkS")
		)
		(fp_poly
			(pts
				(xy -2.2098 -1.4224) (xy -2.2098 1.4224) (xy 2.2098 1.4224) (xy 2.2098 -1.4224)
			)
			(stroke
				(width 0)
				(type default)
			)
			(fill yes)
			(layer "F.SilkS")
		)
		(fp_rect
			(start -2.450084 2.999994)
			(end 2.450084 -2.999994)
			(stroke
				(width 0)
				(type default)
			)
			(fill no)
			(layer "F.CrtYd")
		)
		(fp_poly
			(pts
				(xy -2.8194 3.6322) (xy -2.8194 -3.6322) (xy 2.8194 -3.6322) (xy 2.8194 1.18364) (xy 2.450084 1.18364)
				(xy 2.450084 -2.999994) (xy -2.450084 -2.999994) (xy -2.450084 2.999994) (xy 2.450084 2.999994)
				(xy 2.450084 1.18618) (xy 2.8194 1.18618) (xy 2.8194 3.6322)
			)
			(stroke
				(width 0)
				(type default)
			)
			(fill no)
			(layer "F.CrtYd")
		)
		(fp_rect
			(start -2.8194 3.6322)
			(end 2.8194 -3.6322)
			(stroke
				(width 0)
				(type default)
			)
			(fill no)
			(layer "F.Fab")
		)
		(pad "1" smd rect
			(at -1.905 2.54 90)
			(size 0.635 1.651)
			(layers "F.Cu" "F.Mask" "F.Paste")
			(net "P1V8")
		)
		(pad "2" smd rect
			(at -0.635 2.54 90)
			(size 0.635 1.651)
			(layers "F.Cu" "F.Mask" "F.Paste")
			(net "P1V8")
		)
		(pad "3" smd rect
			(at 0.635 2.54 90)
			(size 0.635 1.651)
			(layers "F.Cu" "F.Mask" "F.Paste")
			(net "P1V8")
		)
		(pad "4" smd rect
			(at 1.905 2.54 90)
			(size 0.635 1.651)
			(layers "F.Cu" "F.Mask" "F.Paste")
			(net "PQ4_D")
		)
		(pad "5" smd rect
			(at 1.905 -2.54 90)
			(size 0.635 1.651)
			(layers "F.Cu" "F.Mask" "F.Paste")
			(net "P1V8_STBY")
		)
		(pad "6" smd rect
			(at 0.635 -2.54 90)
			(size 0.635 1.651)
			(layers "F.Cu" "F.Mask" "F.Paste")
			(net "P1V8_STBY")
		)
		(pad "7" smd rect
			(at -0.635 -2.54 90)
			(size 0.635 1.651)
			(layers "F.Cu" "F.Mask" "F.Paste")
			(net "P1V8_STBY")
		)
		(pad "8" smd rect
			(at -1.905 -2.54 90)
			(size 0.635 1.651)
			(layers "F.Cu" "F.Mask" "F.Paste")
			(net "P1V8_STBY")
		)
	)
)
